FILE_TYPE = MULTI_PHYS_TABLE;
PART 'PI7C9X1172'
{=========================================================================================================================================================================================================}
:PACK_TYPE | MATERIAL | PART_NUMBER     = EnvComp | PART_NUMBER  | JEDEC_TYPE       | DESCRIPTION                 | CLASS | COMPONENT_TYPE | HEIGHT     | LPID    | SPEED_URL | Status |RPL| AML | Bus_Unit | Days ;
{=========================================================================================================================================================================================================}
'QFN'      | 'IC'     | 'H66899-001'(!) = ''      | 'H66899-001' | 'QFN32_20_5MA'   | 'IC,VLSI,OTHER,PI,QFN,32'   | 'IC'  | 'LCC'          | '0.031 IN' | '1650' | 'http://speed.intel.com:8081/speed/module/pdm/item/pdm_item_detail_direct.asp?item_cde=H66899-001&item_rev=01&url_param=unused' | '' | '' | '' | '' | '' 
'QFN'      | 'EMPTY'  | 'H66899-001'(!) = ''      | 'H66899-001' | 'QFN32_20_5MA'   | 'IC,VLSI,OTHER,PI,QFN,32'   | 'IO'  | 'LCC'          | '0.031 IN' | '1650' | 'http://speed.intel.com:8081/speed/module/pdm/item/pdm_item_detail_direct.asp?item_cde=H66899-001&item_rev=01&url_param=unused' | '' | '' | '' | '' | '' 
END_PART
END.
